# T6G (Grand Teton) — schematic netlist excerpt (pin names and nets, part order shuffled) for the footprints in the layout excerpt that follows; sources: Cadence DE-HDL packaged netlist, KiCad conversion of 04192023_DAF0TMB3IC0_F0TG_MB_C_brd_V02_OCP.brd

PU6511  ISL99390FRZTR5935  ISL99390FRZ-TR5935 IC  pkg QFN21_6X5XB  page 365
  VOS  = P0V9_RETIMER_CPU1_VOS1
  AGND  = GND
  VCC  = P0V9_RETIMER_CPU1_VCC1
  PVCC  = P0V9_RETIMER_CPU1_PVCC
  PGND1  = GND
  GL1  = NC_PV09_RETIMER_CPU1_GL1_1
  PGND2  = GND
  SW  = SW_P0V9_RETIMER_CPU1_SW1
  VIN1  = SW_P12V_AUX_P0V9_RETIMER_CPU1_FLT
  VIN2  = SW_P12V_AUX_P0V9_RETIMER_CPU1_FLT
  DNC  = NC_PV09_RETIMER_CPU1_DNC1
  PHASE  = SW_P0V9_RETIMER_CPU1_PH1
  BOOT  = SW_P0V9_RETIMER_CPU1_BOOT1
  PWM  = P0V9_RETIMER_CPU1_PWM1
  EN  = P0V9_RETIMER_CPU1_VCC1
  TOUT_FLT  = P0V9_RETIMER_CPU1_TEMP0
  LSET  = P0V9_RETIMER_CPU1_LSET1
  IOUT  = P0V9_RETIMER_CPU1_IMON1
  REFIN  = PV09_RETIMER_CPU1_VCCS
  PGND3  = GND
  GL2  = NC_PV09_RETIMER_CPU1_GL2_1

(kicad_pcb
	(version 20260206)
	(generator "pcbnew")
	(generator_version "10.0")
	(general
		(thickness 1.6)
		(legacy_teardrops no)
	)
	(paper "A4")
	(title_block
		(title "04192023_DAF0TMB3IC0_F0TG_MB_C_brd_V02_OCP.brd")
		(comment 1 "Grand Teton / footprint 2034 of 8354 (PU6511), pads 1-21 of 21")
	)
	(layers
		(0 "F.Cu" signal "TOP")
		(4 "In1.Cu" signal "GND")
		(6 "In2.Cu" signal "IN1")
		(8 "In3.Cu" signal "GND1")
		(10 "In4.Cu" signal "IN2")
		(12 "In5.Cu" signal "GND2")
		(14 "In6.Cu" signal "IN3")
		(16 "In7.Cu" signal "GND3")
		(18 "In8.Cu" signal "VCC")
		(20 "In9.Cu" signal "VCC1")
		(22 "In10.Cu" signal "GND4")
		(24 "In11.Cu" signal "IN4")
		(26 "In12.Cu" signal "GND5")
		(28 "In13.Cu" signal "IN5")
		(30 "In14.Cu" signal "GND6")
		(32 "In15.Cu" signal "IN6")
		(34 "In16.Cu" signal "GND7")
		(2 "B.Cu" signal "BOTTOM")
		(9 "F.Adhes" user "F.Adhesive")
		(11 "B.Adhes" user "B.Adhesive")
		(13 "F.Paste" user "Package Geometry/Pastemask Top")
		(15 "B.Paste" user "Package Geometry/Pastemask Bottom")
		(5 "F.SilkS" user "Ref Des/Silkscreen Top")
		(7 "B.SilkS" user "Ref Des/Silkscreen Bottom")
		(1 "F.Mask" user "Board Geometry/Soldermask Top")
		(3 "B.Mask" user "Board Geometry/Soldermask Bottom")
		(17 "Dwgs.User" user "User.Drawings")
		(19 "Cmts.User" user "User.Comments")
		(21 "Eco1.User" user "User.Eco1")
		(23 "Eco2.User" user "User.Eco2")
		(25 "Edge.Cuts" user "Board Geometry/Outline")
		(27 "Margin" user)
		(31 "F.CrtYd" user "Package Geometry/Place Bound Top")
		(29 "B.CrtYd" user "Package Geometry/Place Bound Bottom")
		(35 "F.Fab" user "Ref Des/Assembly Top")
		(33 "B.Fab" user "Ref Des/Assembly Bottom")
	)
	(footprint ""
		(layer "F.Cu")
		(at 16.56207 -388.854188)
		(property "Reference" "PU6511"
			(at -5.86232 -8.184642 0)
			(unlocked yes)
			(layer "F.SilkS")
			(effects
				(font
					(size 0.7874 0.5842)
					(thickness 0.1524)
				)
				(justify left)
			)
		)
		(property "Value" ""
			(at 0 0 0)
			(layer "F.Fab")
			(effects
				(font
					(size 1.27 1.27)
				)
			)
		)
		(duplicate_pad_numbers_are_jumpers no)
		(pad "1" smd rect
			(at -2.400046 -2.275078 90)
			(size 0.2286 0.6096)
			(layers "F.Cu" "F.Mask" "F.Paste")
			(net "P0V9_RETIMER_CPU1_VOS1")
		)
		(pad "2" smd rect
			(at -2.400046 -1.82499 90)
			(size 0.2286 0.6096)
			(layers "F.Cu" "F.Mask" "F.Paste")
			(net "GND")
		)
		(pad "3" smd rect
			(at -2.400046 -1.374902 90)
			(size 0.2286 0.6096)
			(layers "F.Cu" "F.Mask" "F.Paste")
			(net "P0V9_RETIMER_CPU1_VCC1")
		)
		(pad "4" smd rect
			(at -2.400046 -0.925068 90)
			(size 0.2286 0.6096)
			(layers "F.Cu" "F.Mask" "F.Paste")
			(net "P0V9_RETIMER_CPU1_PVCC")
		)
		(pad "5" smd rect
			(at -2.400046 -0.47498 90)
			(size 0.2286 0.6096)
			(layers "F.Cu" "F.Mask" "F.Paste")
			(net "GND")
		)
		(pad "6" smd rect
			(at -2.400046 -0.024892 90)
			(size 0.2286 0.6096)
			(layers "F.Cu" "F.Mask" "F.Paste")
			(net "NC_PV09_RETIMER_CPU1_GL1_1")
		)
		(pad "7_9-20_24" smd circle
			(at 0 1.150112 90)
			(size 0 0)
			(layers "F.Cu" "F.Mask" "F.Paste")
			(net "GND")
		)
		(pad "10_19" smd rect
			(at 0 2.899918 90)
			(size 0.6096 4.318)
			(layers "F.Cu" "F.Mask" "F.Paste")
			(net "SW_P0V9_RETIMER_CPU1_SW1")
		)
		(pad "25_29" smd rect
			(at 1.549908 -1.279906 270)
			(size 2.0574 2.3114)
			(layers "F.Cu" "F.Mask" "F.Paste")
			(net "SW_P12V_AUX_P0V9_RETIMER_CPU1_FLT")
		)
		(pad "30" smd rect
			(at 2.05994 -2.899918)
			(size 0.2286 0.6096)
			(layers "F.Cu" "F.Mask" "F.Paste")
			(net "SW_P12V_AUX_P0V9_RETIMER_CPU1_FLT")
		)
		(pad "31" smd rect
			(at 1.610106 -2.899918)
			(size 0.2286 0.6096)
			(layers "F.Cu" "F.Mask" "F.Paste")
			(net "NC_PV09_RETIMER_CPU1_DNC1")
		)
		(pad "32" smd rect
			(at 1.160018 -2.899918)
			(size 0.2286 0.6096)
			(layers "F.Cu" "F.Mask" "F.Paste")
			(net "SW_P0V9_RETIMER_CPU1_PH1")
		)
		(pad "33" smd rect
			(at 0.70993 -2.899918)
			(size 0.2286 0.6096)
			(layers "F.Cu" "F.Mask" "F.Paste")
			(net "SW_P0V9_RETIMER_CPU1_BOOT1")
		)
		(pad "34" smd rect
			(at 0.260096 -2.899918)
			(size 0.2286 0.6096)
			(layers "F.Cu" "F.Mask" "F.Paste")
			(net "P0V9_RETIMER_CPU1_PWM1")
		)
		(pad "35" smd rect
			(at -0.189992 -2.899918)
			(size 0.2286 0.6096)
			(layers "F.Cu" "F.Mask" "F.Paste")
			(net "P0V9_RETIMER_CPU1_VCC1")
		)
		(pad "36" smd rect
			(at -0.64008 -2.899918)
			(size 0.2286 0.6096)
			(layers "F.Cu" "F.Mask" "F.Paste")
			(net "P0V9_RETIMER_CPU1_TEMP0")
		)
		(pad "37" smd rect
			(at -1.089914 -2.899918)
			(size 0.2286 0.6096)
			(layers "F.Cu" "F.Mask" "F.Paste")
			(net "P0V9_RETIMER_CPU1_LSET1")
		)
		(pad "38" smd rect
			(at -1.540002 -2.899918)
			(size 0.2286 0.6096)
			(layers "F.Cu" "F.Mask" "F.Paste")
			(net "P0V9_RETIMER_CPU1_IMON1")
		)
		(pad "39" smd rect
			(at -1.99009 -2.899918)
			(size 0.2286 0.6096)
			(layers "F.Cu" "F.Mask" "F.Paste")
			(net "PV09_RETIMER_CPU1_VCCS")
		)
		(pad "40" smd rect
			(at -0.87503 -1.27508)
			(size 1.7526 1.9558)
			(layers "F.Cu" "F.Mask" "F.Paste")
			(net "GND")
		)
		(pad "41" smd rect
			(at -1.525016 0.249936 270)
			(size 0.3048 0.4572)
			(layers "F.Cu" "F.Mask" "F.Paste")
			(net "NC_PV09_RETIMER_CPU1_GL2_1")
		)
	)
)
